# S9S_MB_2U (Grand Teton) — schematic netlist excerpt (pin names and nets, part order shuffled) for the footprints in the layout excerpt that follows; sources: Cadence DE-HDL packaged netlist, KiCad conversion of 03242023_DA0F0TMBIJ0_F0T_Motherboard_J_brd_V01_OCP.brd

C858  Q_CAP_DIFFBUS  DIFF BUS_0.22UF 6.3V 20% X6S  pkg C0201  page 174 : \1\ = P5E_CPU0_PE1_TX_C_DN<5> ; \2\ = P5E_CPU0_PE1_TX_DN<5>
R3671  Q_RES  0 5% CHIP  pkg 0402LF  page 250 : A = SMB_VR_3V3AUX_SDA_R1 ; B = SMB_SEN_TIC_3V3AUX_SDA
R366  Q_RES  249 1% CHIP  pkg 0402LF  page 218 : A = P3V3_AUX ; B = LED_CPU_RMCA_CATERR

(kicad_pcb
	(version 20260206)
	(generator "pcbnew")
	(generator_version "10.0")
	(general
		(thickness 1.6)
		(legacy_teardrops no)
	)
	(paper "A4")
	(title_block
		(title "03242023_DA0F0TMBIJ0_F0T_Motherboard_J_brd_V01_OCP.brd")
		(comment 1 "Grand Teton / footprints 196-198 of 6105")
	)
	(layers
		(0 "F.Cu" signal "TOP")
		(4 "In1.Cu" signal "GND")
		(6 "In2.Cu" signal "IN1")
		(8 "In3.Cu" signal "GND1")
		(10 "In4.Cu" signal "IN2")
		(12 "In5.Cu" signal "GND2")
		(14 "In6.Cu" signal "IN3")
		(16 "In7.Cu" signal "GND3")
		(18 "In8.Cu" signal "VCC")
		(20 "In9.Cu" signal "VCC1")
		(22 "In10.Cu" signal "GND4")
		(24 "In11.Cu" signal "IN4")
		(26 "In12.Cu" signal "GND5")
		(28 "In13.Cu" signal "IN5")
		(30 "In14.Cu" signal "GND6")
		(32 "In15.Cu" signal "IN6")
		(34 "In16.Cu" signal "GND7")
		(2 "B.Cu" signal "BOTTOM")
		(9 "F.Adhes" user "F.Adhesive")
		(11 "B.Adhes" user "B.Adhesive")
		(13 "F.Paste" user "Package Geometry/Pastemask Top")
		(15 "B.Paste" user "Package Geometry/Pastemask Bottom")
		(5 "F.SilkS" user "Ref Des/Silkscreen Top")
		(7 "B.SilkS" user "Ref Des/Silkscreen Bottom")
		(1 "F.Mask" user "Board Geometry/Soldermask Top")
		(3 "B.Mask" user "Board Geometry/Soldermask Bottom")
		(17 "Dwgs.User" user "User.Drawings")
		(19 "Cmts.User" user "User.Comments")
		(21 "Eco1.User" user "User.Eco1")
		(23 "Eco2.User" user "User.Eco2")
		(25 "Edge.Cuts" user "Board Geometry/Outline")
		(27 "Margin" user)
		(31 "F.CrtYd" user "Package Geometry/Place Bound Top")
		(29 "B.CrtYd" user "Package Geometry/Place Bound Bottom")
		(35 "F.Fab" user "Ref Des/Assembly Top")
		(33 "B.Fab" user "Ref Des/Assembly Bottom")
	)
	(footprint ""
		(layer "F.Cu")
		(at 194.22618 -80.627728)
		(property "Reference" "R366"
			(at 0 0 0)
			(layer "F.SilkS")
			(hide yes)
			(effects
				(font
					(size 1.27 1.27)
				)
			)
		)
		(property "Value" ""
			(at 0 0 0)
			(layer "F.Fab")
			(effects
				(font
					(size 1.27 1.27)
				)
			)
		)
		(duplicate_pad_numbers_are_jumpers no)
		(fp_line
			(start -0.7874 -0.4064)
			(end 0.7874 -0.4064)
			(stroke
				(width 0.1524)
				(type default)
			)
			(layer "F.SilkS")
		)
		(fp_line
			(start -0.7874 0.4064)
			(end -0.7874 -0.4064)
			(stroke
				(width 0.1524)
				(type default)
			)
			(layer "F.SilkS")
		)
		(fp_line
			(start 0.7874 -0.4064)
			(end 0.7874 0.4064)
			(stroke
				(width 0.1524)
				(type default)
			)
			(layer "F.SilkS")
		)
		(fp_line
			(start 0.7874 0.4064)
			(end -0.7874 0.4064)
			(stroke
				(width 0.1524)
				(type default)
			)
			(layer "F.SilkS")
		)
		(fp_line
			(start -0.67945 -0.305054)
			(end -0.12065 -0.305054)
			(stroke
				(width 0.1)
				(type default)
			)
			(layer "F.Fab")
		)
		(fp_line
			(start -0.67945 0.3048)
			(end -0.67945 -0.305054)
			(stroke
				(width 0.1)
				(type default)
			)
			(layer "F.Fab")
		)
		(fp_line
			(start -0.12065 -0.305054)
			(end -0.12065 -0.2794)
			(stroke
				(width 0.1)
				(type default)
			)
			(layer "F.Fab")
		)
		(fp_line
			(start -0.12065 -0.2794)
			(end 0.12065 -0.2794)
			(stroke
				(width 0.1)
				(type default)
			)
			(layer "F.Fab")
		)
		(fp_line
			(start -0.12065 0.2794)
			(end -0.12065 0.3048)
			(stroke
				(width 0.1)
				(type default)
			)
			(layer "F.Fab")
		)
		(fp_line
			(start -0.12065 0.3048)
			(end -0.67945 0.3048)
			(stroke
				(width 0.1)
				(type default)
			)
			(layer "F.Fab")
		)
		(fp_line
			(start 0.120396 0.2794)
			(end -0.12065 0.2794)
			(stroke
				(width 0.1)
				(type default)
			)
			(layer "F.Fab")
		)
		(fp_line
			(start 0.120396 0.3048)
			(end 0.120396 0.2794)
			(stroke
				(width 0.1)
				(type default)
			)
			(layer "F.Fab")
		)
		(fp_line
			(start 0.12065 -0.3048)
			(end 0.67945 -0.3048)
			(stroke
				(width 0.1)
				(type default)
			)
			(layer "F.Fab")
		)
		(fp_line
			(start 0.12065 -0.2794)
			(end 0.12065 -0.3048)
			(stroke
				(width 0.1)
				(type default)
			)
			(layer "F.Fab")
		)
		(fp_line
			(start 0.67945 -0.3048)
			(end 0.67945 0.3048)
			(stroke
				(width 0.1)
				(type default)
			)
			(layer "F.Fab")
		)
		(fp_line
			(start 0.67945 0.3048)
			(end 0.120396 0.3048)
			(stroke
				(width 0.1)
				(type default)
			)
			(layer "F.Fab")
		)
		(pad "1" smd circle
			(at -0.40005 0)
			(size 0 0)
			(layers "F.Cu" "F.Mask" "F.Paste")
			(net "P3V3_AUX")
		)
		(pad "2" smd circle
			(at 0.40005 0)
			(size 0 0)
			(layers "F.Cu" "F.Mask" "F.Paste")
			(net "LED_CPU_RMCA_CATERR")
		)
	)
	(footprint ""
		(layer "F.Cu")
		(at 419.1762 -16.088614 90)
		(property "Reference" "C858"
			(at 0 0 90)
			(layer "F.SilkS")
			(hide yes)
			(effects
				(font
					(size 1.27 1.27)
				)
			)
		)
		(property "Value" ""
			(at 0 0 90)
			(layer "F.Fab")
			(effects
				(font
					(size 1.27 1.27)
				)
			)
		)
		(duplicate_pad_numbers_are_jumpers no)
		(fp_line
			(start 0.299974 -0.150114)
			(end 0.299974 0.150114)
			(stroke
				(width 0.1)
				(type default)
			)
			(layer "F.Fab")
		)
		(fp_line
			(start -0.299974 -0.150114)
			(end 0.299974 -0.150114)
			(stroke
				(width 0.1)
				(type default)
			)
			(layer "F.Fab")
		)
		(fp_line
			(start 0.299974 0.150114)
			(end -0.299974 0.150114)
			(stroke
				(width 0.1)
				(type default)
			)
			(layer "F.Fab")
		)
		(fp_line
			(start -0.299974 0.150114)
			(end -0.299974 -0.150114)
			(stroke
				(width 0.1)
				(type default)
			)
			(layer "F.Fab")
		)
		(pad "1" smd rect
			(at -0.2667 0 90)
			(size 0.3048 0.381)
			(layers "F.Cu" "F.Mask" "F.Paste")
			(net "P5E_CPU0_PE1_TX_C_DN<5>")
		)
		(pad "2" smd rect
			(at 0.2667 0 90)
			(size 0.3048 0.381)
			(layers "F.Cu" "F.Mask" "F.Paste")
			(net "P5E_CPU0_PE1_TX_DN<5>")
		)
	)
	(footprint ""
		(layer "F.Cu")
		(at 22.809454 -112.399826)
		(property "Reference" "R3671"
			(at 0 0 0)
			(layer "F.SilkS")
			(hide yes)
			(effects
				(font
					(size 1.27 1.27)
				)
			)
		)
		(property "Value" ""
			(at 0 0 0)
			(layer "F.Fab")
			(effects
				(font
					(size 1.27 1.27)
				)
			)
		)
		(duplicate_pad_numbers_are_jumpers no)
		(fp_line
			(start -0.7874 -0.4064)
			(end 0.7874 -0.4064)
			(stroke
				(width 0.1524)
				(type default)
			)
			(layer "F.SilkS")
		)
		(fp_line
			(start -0.7874 0.4064)
			(end -0.7874 -0.4064)
			(stroke
				(width 0.1524)
				(type default)
			)
			(layer "F.SilkS")
		)
		(fp_line
			(start 0.7874 -0.4064)
			(end 0.7874 0.4064)
			(stroke
				(width 0.1524)
				(type default)
			)
			(layer "F.SilkS")
		)
		(fp_line
			(start 0.7874 0.4064)
			(end -0.7874 0.4064)
			(stroke
				(width 0.1524)
				(type default)
			)
			(layer "F.SilkS")
		)
		(fp_line
			(start -0.67945 -0.305054)
			(end -0.12065 -0.305054)
			(stroke
				(width 0.1)
				(type default)
			)
			(layer "F.Fab")
		)
		(fp_line
			(start -0.67945 0.3048)
			(end -0.67945 -0.305054)
			(stroke
				(width 0.1)
				(type default)
			)
			(layer "F.Fab")
		)
		(fp_line
			(start -0.12065 -0.305054)
			(end -0.12065 -0.2794)
			(stroke
				(width 0.1)
				(type default)
			)
			(layer "F.Fab")
		)
		(fp_line
			(start -0.12065 -0.2794)
			(end 0.12065 -0.2794)
			(stroke
				(width 0.1)
				(type default)
			)
			(layer "F.Fab")
		)
		(fp_line
			(start -0.12065 0.2794)
			(end -0.12065 0.3048)
			(stroke
				(width 0.1)
				(type default)
			)
			(layer "F.Fab")
		)
		(fp_line
			(start -0.12065 0.3048)
			(end -0.67945 0.3048)
			(stroke
				(width 0.1)
				(type default)
			)
			(layer "F.Fab")
		)
		(fp_line
			(start 0.120396 0.2794)
			(end -0.12065 0.2794)
			(stroke
				(width 0.1)
				(type default)
			)
			(layer "F.Fab")
		)
		(fp_line
			(start 0.120396 0.3048)
			(end 0.120396 0.2794)
			(stroke
				(width 0.1)
				(type default)
			)
			(layer "F.Fab")
		)
		(fp_line
			(start 0.12065 -0.3048)
			(end 0.67945 -0.3048)
			(stroke
				(width 0.1)
				(type default)
			)
			(layer "F.Fab")
		)
		(fp_line
			(start 0.12065 -0.2794)
			(end 0.12065 -0.3048)
			(stroke
				(width 0.1)
				(type default)
			)
			(layer "F.Fab")
		)
		(fp_line
			(start 0.67945 -0.3048)
			(end 0.67945 0.3048)
			(stroke
				(width 0.1)
				(type default)
			)
			(layer "F.Fab")
		)
		(fp_line
			(start 0.67945 0.3048)
			(end 0.120396 0.3048)
			(stroke
				(width 0.1)
				(type default)
			)
			(layer "F.Fab")
		)
		(pad "1" smd circle
			(at -0.40005 0)
			(size 0 0)
			(layers "F.Cu" "F.Mask" "F.Paste")
			(net "SMB_VR_3V3AUX_SDA_R1")
		)
		(pad "2" smd circle
			(at 0.40005 0)
			(size 0 0)
			(layers "F.Cu" "F.Mask" "F.Paste")
			(net "SMB_SEN_TIC_3V3AUX_SDA")
		)
	)
)
